(kicad_pcb
	(version 20260206)
	(generator "pcbnew")
	(generator_version "10.0")
	(general
		(thickness 1.6)
		(legacy_teardrops no)
	)
	(paper "A4")
	(title_block
		(title "01162023_DA0F0TEBIF0_F0T_Expander_BD_F_brd_V02_OCP.brd")
		(comment 1 "Grand Teton / footprints 8798-8804 of 9728")
	)
	(layers
		(0 "F.Cu" signal "TOP")
		(4 "In1.Cu" signal "GND")
		(6 "In2.Cu" signal "VCC")
		(8 "In3.Cu" signal "VCC1")
		(10 "In4.Cu" signal "GND1")
		(12 "In5.Cu" signal "IN1")
		(14 "In6.Cu" signal "GND2")
		(16 "In7.Cu" signal "IN2")
		(18 "In8.Cu" signal "GND3")
		(20 "In9.Cu" signal "IN3")
		(22 "In10.Cu" signal "GND4")
		(24 "In11.Cu" signal "IN4")
		(26 "In12.Cu" signal "GND5")
		(28 "In13.Cu" signal "IN5")
		(30 "In14.Cu" signal "GND6")
		(32 "In15.Cu" signal "IN6")
		(34 "In16.Cu" signal "GND7")
		(2 "B.Cu" signal "BOTTOM")
		(9 "F.Adhes" user "F.Adhesive")
		(11 "B.Adhes" user "B.Adhesive")
		(13 "F.Paste" user "Package Geometry/Pastemask Top")
		(15 "B.Paste" user "Package Geometry/Pastemask Bottom")
		(5 "F.SilkS" user "Ref Des/Silkscreen Top")
		(7 "B.SilkS" user "Ref Des/Silkscreen Bottom")
		(1 "F.Mask" user "Board Geometry/Soldermask Top")
		(3 "B.Mask" user "Board Geometry/Soldermask Bottom")
		(17 "Dwgs.User" user "User.Drawings")
		(19 "Cmts.User" user "User.Comments")
		(21 "Eco1.User" user "User.Eco1")
		(23 "Eco2.User" user "User.Eco2")
		(25 "Edge.Cuts" user "Board Geometry/Outline")
		(27 "Margin" user)
		(31 "F.CrtYd" user "Package Geometry/Place Bound Top")
		(29 "B.CrtYd" user "Package Geometry/Place Bound Bottom")
		(35 "F.Fab" user "Ref Des/Assembly Top")
		(33 "B.Fab" user "Ref Des/Assembly Bottom")
	)
	(footprint ""
		(layer "B.Cu")
		(at 346.026232 -323.15531 -90)
		(property "Reference" "R6514"
			(at 0 0 90)
			(layer "B.SilkS")
			(hide yes)
			(effects
				(font
					(size 1.27 1.27)
				)
				(justify mirror)
			)
		)
		(property "Value" ""
			(at 0 0 90)
			(layer "B.Fab")
			(effects
				(font
					(size 1.27 1.27)
				)
				(justify mirror)
			)
		)
		(duplicate_pad_numbers_are_jumpers no)
		(fp_line
			(start -0.7874 0.4064)
			(end 0.7874 0.4064)
			(stroke
				(width 0.1524)
				(type default)
			)
			(layer "B.SilkS")
		)
		(fp_line
			(start 0.7874 0.4064)
			(end 0.7874 -0.4064)
			(stroke
				(width 0.1524)
				(type default)
			)
			(layer "B.SilkS")
		)
		(fp_line
			(start -0.7874 -0.4064)
			(end -0.7874 0.4064)
			(stroke
				(width 0.1524)
				(type default)
			)
			(layer "B.SilkS")
		)
		(fp_line
			(start 0.7874 -0.4064)
			(end -0.7874 -0.4064)
			(stroke
				(width 0.1524)
				(type default)
			)
			(layer "B.SilkS")
		)
		(fp_line
			(start -0.67945 0.3048)
			(end -0.120396 0.3048)
			(stroke
				(width 0.1)
				(type default)
			)
			(layer "B.Fab")
		)
		(fp_line
			(start -0.120396 0.3048)
			(end -0.120396 0.2794)
			(stroke
				(width 0.1)
				(type default)
			)
			(layer "B.Fab")
		)
		(fp_line
			(start 0.12065 0.3048)
			(end 0.67945 0.3048)
			(stroke
				(width 0.1)
				(type default)
			)
			(layer "B.Fab")
		)
		(fp_line
			(start 0.67945 0.3048)
			(end 0.67945 -0.305054)
			(stroke
				(width 0.1)
				(type default)
			)
			(layer "B.Fab")
		)
		(fp_line
			(start -0.120396 0.2794)
			(end 0.12065 0.2794)
			(stroke
				(width 0.1)
				(type default)
			)
			(layer "B.Fab")
		)
		(fp_line
			(start 0.12065 0.2794)
			(end 0.12065 0.3048)
			(stroke
				(width 0.1)
				(type default)
			)
			(layer "B.Fab")
		)
		(fp_line
			(start -0.12065 -0.2794)
			(end -0.12065 -0.3048)
			(stroke
				(width 0.1)
				(type default)
			)
			(layer "B.Fab")
		)
		(fp_line
			(start 0.12065 -0.2794)
			(end -0.12065 -0.2794)
			(stroke
				(width 0.1)
				(type default)
			)
			(layer "B.Fab")
		)
		(fp_line
			(start -0.67945 -0.3048)
			(end -0.67945 0.3048)
			(stroke
				(width 0.1)
				(type default)
			)
			(layer "B.Fab")
		)
		(fp_line
			(start -0.12065 -0.3048)
			(end -0.67945 -0.3048)
			(stroke
				(width 0.1)
				(type default)
			)
			(layer "B.Fab")
		)
		(fp_line
			(start 0.12065 -0.305054)
			(end 0.12065 -0.2794)
			(stroke
				(width 0.1)
				(type default)
			)
			(layer "B.Fab")
		)
		(fp_line
			(start 0.67945 -0.305054)
			(end 0.12065 -0.305054)
			(stroke
				(width 0.1)
				(type default)
			)
			(layer "B.Fab")
		)
		(pad "1" smd circle
			(at 0.40005 0 90)
			(size 0 0)
			(layers "B.Cu" "B.Mask" "B.Paste")
			(net "P0V8_SERDES_VDDA_PEX2")
		)
		(pad "2" smd circle
			(at -0.40005 0 90)
			(size 0 0)
			(layers "B.Cu" "B.Mask" "B.Paste")
			(net "P0V8_SERDES_VDDA_PEX2_C7")
		)
	)
	(footprint ""
		(layer "B.Cu")
		(at 408.899868 -290.199826 90)
		(property "Reference" "C1962"
			(at 0 0 90)
			(layer "B.SilkS")
			(hide yes)
			(effects
				(font
					(size 1.27 1.27)
				)
				(justify mirror)
			)
		)
		(property "Value" ""
			(at 0 0 90)
			(layer "B.Fab")
			(effects
				(font
					(size 1.27 1.27)
				)
				(justify mirror)
			)
		)
		(duplicate_pad_numbers_are_jumpers no)
		(fp_line
			(start 0.299974 -0.150114)
			(end -0.299974 -0.150114)
			(stroke
				(width 0.1)
				(type default)
			)
			(layer "B.Fab")
		)
		(fp_line
			(start -0.299974 -0.150114)
			(end -0.299974 0.150114)
			(stroke
				(width 0.1)
				(type default)
			)
			(layer "B.Fab")
		)
		(fp_line
			(start 0.299974 0.150114)
			(end 0.299974 -0.150114)
			(stroke
				(width 0.1)
				(type default)
			)
			(layer "B.Fab")
		)
		(fp_line
			(start -0.299974 0.150114)
			(end 0.299974 0.150114)
			(stroke
				(width 0.1)
				(type default)
			)
			(layer "B.Fab")
		)
		(pad "1" smd rect
			(at 0.2667 0 270)
			(size 0.3048 0.381)
			(layers "B.Cu" "B.Mask" "B.Paste")
			(net "P0V8_SERDES_VDDA_PEX3")
		)
		(pad "2" smd rect
			(at -0.2667 0 270)
			(size 0.3048 0.381)
			(layers "B.Cu" "B.Mask" "B.Paste")
			(net "GND")
		)
	)
	(footprint ""
		(layer "B.Cu")
		(at 228.29901 -143.815054 -90)
		(property "Reference" "C2806"
			(at 0 0 90)
			(layer "B.SilkS")
			(hide yes)
			(effects
				(font
					(size 1.27 1.27)
				)
				(justify mirror)
			)
		)
		(property "Value" ""
			(at 0 0 90)
			(layer "B.Fab")
			(effects
				(font
					(size 1.27 1.27)
				)
				(justify mirror)
			)
		)
		(duplicate_pad_numbers_are_jumpers no)
		(fp_line
			(start -0.7874 0.4064)
			(end 0.7874 0.4064)
			(stroke
				(width 0.1524)
				(type default)
			)
			(layer "B.SilkS")
		)
		(fp_line
			(start 0.7874 0.4064)
			(end 0.7874 -0.4064)
			(stroke
				(width 0.1524)
				(type default)
			)
			(layer "B.SilkS")
		)
		(fp_line
			(start -0.7874 -0.4064)
			(end -0.7874 0.4064)
			(stroke
				(width 0.1524)
				(type default)
			)
			(layer "B.SilkS")
		)
		(fp_line
			(start 0.7874 -0.4064)
			(end -0.7874 -0.4064)
			(stroke
				(width 0.1524)
				(type default)
			)
			(layer "B.SilkS")
		)
		(fp_line
			(start -0.67945 0.3048)
			(end -0.120396 0.3048)
			(stroke
				(width 0.1)
				(type default)
			)
			(layer "B.Fab")
		)
		(fp_line
			(start -0.120396 0.3048)
			(end -0.120396 0.2794)
			(stroke
				(width 0.1)
				(type default)
			)
			(layer "B.Fab")
		)
		(fp_line
			(start 0.12065 0.3048)
			(end 0.67945 0.3048)
			(stroke
				(width 0.1)
				(type default)
			)
			(layer "B.Fab")
		)
		(fp_line
			(start 0.67945 0.3048)
			(end 0.67945 -0.305054)
			(stroke
				(width 0.1)
				(type default)
			)
			(layer "B.Fab")
		)
		(fp_line
			(start -0.120396 0.2794)
			(end 0.12065 0.2794)
			(stroke
				(width 0.1)
				(type default)
			)
			(layer "B.Fab")
		)
		(fp_line
			(start 0.12065 0.2794)
			(end 0.12065 0.3048)
			(stroke
				(width 0.1)
				(type default)
			)
			(layer "B.Fab")
		)
		(fp_line
			(start -0.12065 -0.2794)
			(end -0.12065 -0.3048)
			(stroke
				(width 0.1)
				(type default)
			)
			(layer "B.Fab")
		)
		(fp_line
			(start 0.12065 -0.2794)
			(end -0.12065 -0.2794)
			(stroke
				(width 0.1)
				(type default)
			)
			(layer "B.Fab")
		)
		(fp_line
			(start -0.67945 -0.3048)
			(end -0.67945 0.3048)
			(stroke
				(width 0.1)
				(type default)
			)
			(layer "B.Fab")
		)
		(fp_line
			(start -0.12065 -0.3048)
			(end -0.67945 -0.3048)
			(stroke
				(width 0.1)
				(type default)
			)
			(layer "B.Fab")
		)
		(fp_line
			(start 0.12065 -0.305054)
			(end 0.12065 -0.2794)
			(stroke
				(width 0.1)
				(type default)
			)
			(layer "B.Fab")
		)
		(fp_line
			(start 0.67945 -0.305054)
			(end 0.12065 -0.305054)
			(stroke
				(width 0.1)
				(type default)
			)
			(layer "B.Fab")
		)
		(pad "1" smd circle
			(at 0.40005 0 90)
			(size 0 0)
			(layers "B.Cu" "B.Mask" "B.Paste")
			(net "P3V3_CLK_GEN_VDDPT_CK440_PEX")
		)
		(pad "2" smd circle
			(at -0.40005 0 90)
			(size 0 0)
			(layers "B.Cu" "B.Mask" "B.Paste")
			(net "GND")
		)
	)
	(footprint ""
		(layer "B.Cu")
		(at 309.741824 -99.037648 180)
		(property "Reference" "R269"
			(at 0 0 0)
			(layer "B.SilkS")
			(hide yes)
			(effects
				(font
					(size 1.27 1.27)
				)
				(justify mirror)
			)
		)
		(property "Value" ""
			(at 0 0 0)
			(layer "B.Fab")
			(effects
				(font
					(size 1.27 1.27)
				)
				(justify mirror)
			)
		)
		(duplicate_pad_numbers_are_jumpers no)
		(fp_line
			(start 0.7874 0.4064)
			(end 0.7874 -0.4064)
			(stroke
				(width 0.1524)
				(type default)
			)
			(layer "B.SilkS")
		)
		(fp_line
			(start 0.7874 -0.4064)
			(end -0.7874 -0.4064)
			(stroke
				(width 0.1524)
				(type default)
			)
			(layer "B.SilkS")
		)
		(fp_line
			(start -0.7874 0.4064)
			(end 0.7874 0.4064)
			(stroke
				(width 0.1524)
				(type default)
			)
			(layer "B.SilkS")
		)
		(fp_line
			(start -0.7874 -0.4064)
			(end -0.7874 0.4064)
			(stroke
				(width 0.1524)
				(type default)
			)
			(layer "B.SilkS")
		)
		(fp_line
			(start 0.67945 0.3048)
			(end 0.67945 -0.305054)
			(stroke
				(width 0.1)
				(type default)
			)
			(layer "B.Fab")
		)
		(fp_line
			(start 0.67945 -0.305054)
			(end 0.12065 -0.305054)
			(stroke
				(width 0.1)
				(type default)
			)
			(layer "B.Fab")
		)
		(fp_line
			(start 0.12065 0.3048)
			(end 0.67945 0.3048)
			(stroke
				(width 0.1)
				(type default)
			)
			(layer "B.Fab")
		)
		(fp_line
			(start 0.12065 0.2794)
			(end 0.12065 0.3048)
			(stroke
				(width 0.1)
				(type default)
			)
			(layer "B.Fab")
		)
		(fp_line
			(start 0.12065 -0.2794)
			(end -0.12065 -0.2794)
			(stroke
				(width 0.1)
				(type default)
			)
			(layer "B.Fab")
		)
		(fp_line
			(start 0.12065 -0.305054)
			(end 0.12065 -0.2794)
			(stroke
				(width 0.1)
				(type default)
			)
			(layer "B.Fab")
		)
		(fp_line
			(start -0.120396 0.3048)
			(end -0.120396 0.2794)
			(stroke
				(width 0.1)
				(type default)
			)
			(layer "B.Fab")
		)
		(fp_line
			(start -0.120396 0.2794)
			(end 0.12065 0.2794)
			(stroke
				(width 0.1)
				(type default)
			)
			(layer "B.Fab")
		)
		(fp_line
			(start -0.12065 -0.2794)
			(end -0.12065 -0.3048)
			(stroke
				(width 0.1)
				(type default)
			)
			(layer "B.Fab")
		)
		(fp_line
			(start -0.12065 -0.3048)
			(end -0.67945 -0.3048)
			(stroke
				(width 0.1)
				(type default)
			)
			(layer "B.Fab")
		)
		(fp_line
			(start -0.67945 0.3048)
			(end -0.120396 0.3048)
			(stroke
				(width 0.1)
				(type default)
			)
			(layer "B.Fab")
		)
		(fp_line
			(start -0.67945 -0.3048)
			(end -0.67945 0.3048)
			(stroke
				(width 0.1)
				(type default)
			)
			(layer "B.Fab")
		)
		(pad "1" smd circle
			(at 0.40005 0)
			(size 0 0)
			(layers "B.Cu" "B.Mask" "B.Paste")
			(net "NIC5_CLK")
		)
		(pad "2" smd circle
			(at -0.40005 0)
			(size 0 0)
			(layers "B.Cu" "B.Mask" "B.Paste")
			(net "GND")
		)
	)
	(footprint ""
		(layer "B.Cu")
		(at 107.837986 -357.638604 90)
		(property "Reference" "L149"
			(at -1.393698 1.636776 270)
			(unlocked yes)
			(layer "B.SilkS")
			(effects
				(font
					(size 0.7874 0.5842)
					(thickness 0.1524)
				)
				(justify left mirror)
			)
		)
		(property "Value" ""
			(at 0 0 90)
			(layer "B.Fab")
			(effects
				(font
					(size 1.27 1.27)
				)
				(justify mirror)
			)
		)
		(duplicate_pad_numbers_are_jumpers no)
		(fp_line
			(start 1.63576 -0.8128)
			(end -1.63576 -0.8128)
			(stroke
				(width 0.1524)
				(type default)
			)
			(layer "B.SilkS")
		)
		(fp_line
			(start 1.63576 -0.8128)
			(end 1.63576 0.8128)
			(stroke
				(width 0.1524)
				(type default)
			)
			(layer "B.SilkS")
		)
		(fp_line
			(start -1.63576 -0.8128)
			(end -1.63576 0.8128)
			(stroke
				(width 0.1524)
				(type default)
			)
			(layer "B.SilkS")
		)
		(fp_line
			(start -1.63576 0.8128)
			(end 1.63576 0.8128)
			(stroke
				(width 0.1524)
				(type default)
			)
			(layer "B.SilkS")
		)
		(fp_line
			(start 1.56083 -0.738632)
			(end 1.56083 0.7366)
			(stroke
				(width 0.1)
				(type default)
			)
			(layer "B.Fab")
		)
		(fp_line
			(start -1.560576 -0.738632)
			(end 1.56083 -0.738632)
			(stroke
				(width 0.1)
				(type default)
			)
			(layer "B.Fab")
		)
		(fp_line
			(start 1.56083 0.7366)
			(end 1.524 0.7366)
			(stroke
				(width 0.1)
				(type default)
			)
			(layer "B.Fab")
		)
		(fp_line
			(start 1.524 0.7366)
			(end -1.524 0.7366)
			(stroke
				(width 0.1)
				(type default)
			)
			(layer "B.Fab")
		)
		(fp_line
			(start -1.524 0.7366)
			(end -1.560576 0.7366)
			(stroke
				(width 0.1)
				(type default)
			)
			(layer "B.Fab")
		)
		(fp_line
			(start -1.560576 0.7366)
			(end -1.560576 -0.738632)
			(stroke
				(width 0.1)
				(type default)
			)
			(layer "B.Fab")
		)
		(pad "1" smd rect
			(at 0.94996 0 90)
			(size 1.1176 1.3716)
			(layers "B.Cu" "B.Mask" "B.Paste")
			(net "P3V3")
		)
		(pad "2" smd rect
			(at -0.94996 0 90)
			(size 1.1176 1.3716)
			(layers "B.Cu" "B.Mask" "B.Paste")
			(net "P3V3_CLK_BUFFER_9ZXL0451E_S3_VZX3P3")
		)
	)
	(footprint ""
		(layer "B.Cu")
		(at 359.455974 -321.84594 -90)
		(property "Reference" "R6545"
			(at 0 0 90)
			(layer "B.SilkS")
			(hide yes)
			(effects
				(font
					(size 1.27 1.27)
				)
				(justify mirror)
			)
		)
		(property "Value" ""
			(at 0 0 90)
			(layer "B.Fab")
			(effects
				(font
					(size 1.27 1.27)
				)
				(justify mirror)
			)
		)
		(duplicate_pad_numbers_are_jumpers no)
		(fp_line
			(start -0.7874 0.4064)
			(end 0.7874 0.4064)
			(stroke
				(width 0.1524)
				(type default)
			)
			(layer "B.SilkS")
		)
		(fp_line
			(start 0.7874 0.4064)
			(end 0.7874 -0.4064)
			(stroke
				(width 0.1524)
				(type default)
			)
			(layer "B.SilkS")
		)
		(fp_line
			(start -0.7874 -0.4064)
			(end -0.7874 0.4064)
			(stroke
				(width 0.1524)
				(type default)
			)
			(layer "B.SilkS")
		)
		(fp_line
			(start 0.7874 -0.4064)
			(end -0.7874 -0.4064)
			(stroke
				(width 0.1524)
				(type default)
			)
			(layer "B.SilkS")
		)
		(fp_line
			(start -0.67945 0.3048)
			(end -0.120396 0.3048)
			(stroke
				(width 0.1)
				(type default)
			)
			(layer "B.Fab")
		)
		(fp_line
			(start -0.120396 0.3048)
			(end -0.120396 0.2794)
			(stroke
				(width 0.1)
				(type default)
			)
			(layer "B.Fab")
		)
		(fp_line
			(start 0.12065 0.3048)
			(end 0.67945 0.3048)
			(stroke
				(width 0.1)
				(type default)
			)
			(layer "B.Fab")
		)
		(fp_line
			(start 0.67945 0.3048)
			(end 0.67945 -0.305054)
			(stroke
				(width 0.1)
				(type default)
			)
			(layer "B.Fab")
		)
		(fp_line
			(start -0.120396 0.2794)
			(end 0.12065 0.2794)
			(stroke
				(width 0.1)
				(type default)
			)
			(layer "B.Fab")
		)
		(fp_line
			(start 0.12065 0.2794)
			(end 0.12065 0.3048)
			(stroke
				(width 0.1)
				(type default)
			)
			(layer "B.Fab")
		)
		(fp_line
			(start -0.12065 -0.2794)
			(end -0.12065 -0.3048)
			(stroke
				(width 0.1)
				(type default)
			)
			(layer "B.Fab")
		)
		(fp_line
			(start 0.12065 -0.2794)
			(end -0.12065 -0.2794)
			(stroke
				(width 0.1)
				(type default)
			)
			(layer "B.Fab")
		)
		(fp_line
			(start -0.67945 -0.3048)
			(end -0.67945 0.3048)
			(stroke
				(width 0.1)
				(type default)
			)
			(layer "B.Fab")
		)
		(fp_line
			(start -0.12065 -0.3048)
			(end -0.67945 -0.3048)
			(stroke
				(width 0.1)
				(type default)
			)
			(layer "B.Fab")
		)
		(fp_line
			(start 0.12065 -0.305054)
			(end 0.12065 -0.2794)
			(stroke
				(width 0.1)
				(type default)
			)
			(layer "B.Fab")
		)
		(fp_line
			(start 0.67945 -0.305054)
			(end 0.12065 -0.305054)
			(stroke
				(width 0.1)
				(type default)
			)
			(layer "B.Fab")
		)
		(pad "1" smd circle
			(at 0.40005 0 90)
			(size 0 0)
			(layers "B.Cu" "B.Mask" "B.Paste")
			(net "P0V8_SERDES_VDDA_PEX3")
		)
		(pad "2" smd circle
			(at -0.40005 0 90)
			(size 0 0)
			(layers "B.Cu" "B.Mask" "B.Paste")
			(net "P0V8_SERDES_VDDA_PEX3_C8")
		)
	)
	(footprint ""
		(layer "B.Cu")
		(at 295.575228 -110.497366 180)
		(property "Reference" "R289"
			(at 0 0 0)
			(layer "B.SilkS")
			(hide yes)
			(effects
				(font
					(size 1.27 1.27)
				)
				(justify mirror)
			)
		)
		(property "Value" ""
			(at 0 0 0)
			(layer "B.Fab")
			(effects
				(font
					(size 1.27 1.27)
				)
				(justify mirror)
			)
		)
		(duplicate_pad_numbers_are_jumpers no)
		(fp_line
			(start 0.7874 0.4064)
			(end 0.7874 -0.4064)
			(stroke
				(width 0.1524)
				(type default)
			)
			(layer "B.SilkS")
		)
		(fp_line
			(start 0.7874 -0.4064)
			(end -0.7874 -0.4064)
			(stroke
				(width 0.1524)
				(type default)
			)
			(layer "B.SilkS")
		)
		(fp_line
			(start -0.7874 0.4064)
			(end 0.7874 0.4064)
			(stroke
				(width 0.1524)
				(type default)
			)
			(layer "B.SilkS")
		)
		(fp_line
			(start -0.7874 -0.4064)
			(end -0.7874 0.4064)
			(stroke
				(width 0.1524)
				(type default)
			)
			(layer "B.SilkS")
		)
		(fp_line
			(start 0.67945 0.3048)
			(end 0.67945 -0.305054)
			(stroke
				(width 0.1)
				(type default)
			)
			(layer "B.Fab")
		)
		(fp_line
			(start 0.67945 -0.305054)
			(end 0.12065 -0.305054)
			(stroke
				(width 0.1)
				(type default)
			)
			(layer "B.Fab")
		)
		(fp_line
			(start 0.12065 0.3048)
			(end 0.67945 0.3048)
			(stroke
				(width 0.1)
				(type default)
			)
			(layer "B.Fab")
		)
		(fp_line
			(start 0.12065 0.2794)
			(end 0.12065 0.3048)
			(stroke
				(width 0.1)
				(type default)
			)
			(layer "B.Fab")
		)
		(fp_line
			(start 0.12065 -0.2794)
			(end -0.12065 -0.2794)
			(stroke
				(width 0.1)
				(type default)
			)
			(layer "B.Fab")
		)
		(fp_line
			(start 0.12065 -0.305054)
			(end 0.12065 -0.2794)
			(stroke
				(width 0.1)
				(type default)
			)
			(layer "B.Fab")
		)
		(fp_line
			(start -0.120396 0.3048)
			(end -0.120396 0.2794)
			(stroke
				(width 0.1)
				(type default)
			)
			(layer "B.Fab")
		)
		(fp_line
			(start -0.120396 0.2794)
			(end 0.12065 0.2794)
			(stroke
				(width 0.1)
				(type default)
			)
			(layer "B.Fab")
		)
		(fp_line
			(start -0.12065 -0.2794)
			(end -0.12065 -0.3048)
			(stroke
				(width 0.1)
				(type default)
			)
			(layer "B.Fab")
		)
		(fp_line
			(start -0.12065 -0.3048)
			(end -0.67945 -0.3048)
			(stroke
				(width 0.1)
				(type default)
			)
			(layer "B.Fab")
		)
		(fp_line
			(start -0.67945 0.3048)
			(end -0.120396 0.3048)
			(stroke
				(width 0.1)
				(type default)
			)
			(layer "B.Fab")
		)
		(fp_line
			(start -0.67945 -0.3048)
			(end -0.67945 0.3048)
			(stroke
				(width 0.1)
				(type default)
			)
			(layer "B.Fab")
		)
		(pad "1" smd circle
			(at 0.40005 0)
			(size 0 0)
			(layers "B.Cu" "B.Mask" "B.Paste")
			(net "NIC5_BIF2_N")
		)
		(pad "2" smd circle
			(at -0.40005 0)
			(size 0 0)
			(layers "B.Cu" "B.Mask" "B.Paste")
			(net "GND")
		)
	)
)
